# T6G (Grand Teton) — schematic netlist excerpt (pin names and nets, part order shuffled) for the footprints in the layout excerpt that follows; sources: Cadence DE-HDL packaged netlist, KiCad conversion of 04192023_DAF0TMB3IC0_F0TG_MB_C_brd_V02_OCP.brd

J67  SCONN288_DDR506112002KQ  IO  pkg DDR288S_1-1VXC  page 97
  VIN_BULK0  = P12V_MEM_CPU0
  RFU0  = NC
  VIN_MGMT  = P3V3_AUX
  HSCL  = I3C_SPD_DDRL_CPU0_SCL
  HSDA  = I3C_SPD_DDRL_CPU0_SDA
  VSS0  = GND
  DQ0_A  = M_L_CPU0_SA_DQ<0>
  VSS1  = GND
  DQ1_A  = M_L_CPU0_SA_DQ<1>
  VSS2  = GND
  DQS0_A_T  = M_L_CPU0_SA_DQS_DP<0>
  DQS0_A_C  = M_L_CPU0_SA_DQS_DN<0>
  VSS3  = GND
  DQ4_A  = M_L_CPU0_SA_DQ<4>
  VSS4  = GND
  DQ5_A  = M_L_CPU0_SA_DQ<5>
  VSS5  = GND
  DQ8_A  = M_L_CPU0_SA_DQ<8>
  VSS6  = GND
  DQ9_A  = M_L_CPU0_SA_DQ<9>
  VSS7  = GND
  DQS1_A_T  = M_L_CPU0_SA_DQS_DP<1>
  DQS1_A_C  = M_L_CPU0_SA_DQS_DN<1>
  VSS8  = GND
  DQ12_A  = M_L_CPU0_SA_DQ<12>
  VSS9  = GND
  DQ13_A  = M_L_CPU0_SA_DQ<13>
  VSS10  = GND
  DQ16_A  = M_L_CPU0_SA_DQ<16>
  VSS11  = GND
  DQ17_A  = M_L_CPU0_SA_DQ<17>
  VSS12  = GND
  DQS2_A_T  = M_L_CPU0_SA_DQS_DP<2>
  DQS2_A_C  = M_L_CPU0_SA_DQS_DN<2>
  VSS13  = GND
  DQ20_A  = M_L_CPU0_SA_DQ<20>
  VSS14  = GND
  DQ21_A  = M_L_CPU0_SA_DQ<21>
  VSS15  = GND
  DQ24_A  = M_L_CPU0_SA_DQ<24>
  VSS16  = GND
  DQ25_A  = M_L_CPU0_SA_DQ<25>
  VSS17  = GND
  DQS3_A_T  = M_L_CPU0_SA_DQS_DP<3>
  DQS3_A_C  = M_L_CPU0_SA_DQS_DN<3>
  VSS18  = GND
  DQ28_A  = M_L_CPU0_SA_DQ<28>
  VSS19  = GND
  DQ29_A  = M_L_CPU0_SA_DQ<29>
  VSS20  = GND
  CB0_A  = M_L_CPU0_SA_CB<0>
  VSS21  = GND
  CB1_A  = M_L_CPU0_SA_CB<1>
  VSS22  = GND
  DQS4_A_T  = M_L_CPU0_SA_DQS_DP<4>
  DQS4_A_C  = M_L_CPU0_SA_DQS_DN<4>
  VSS23  = GND
  CB4_A  = M_L_CPU0_SA_CB<4>
  VSS24  = GND
  CB5_A  = M_L_CPU0_SA_CB<5>
  VSS25  = GND
  ALERT_N  = M_L_CPU0_ALERT_N
  VSS26  = GND
  CS0_A_N  = M_L_CPU0_SA_CS_N<0>
  VSS27  = GND
  CA0_A  = M_L_CPU0_SA_CA<0>
  VSS28  = GND
  CA2_A  = M_L_CPU0_SA_CA<2>
  VSS29  = GND
  CA4_A  = M_L_CPU0_SA_CA<4>
  VSS30  = GND
  CA6_A  = M_L_CPU0_SA_CA<6>
  VSS31  = GND
  PAR_A  = M_L_CPU0_SA_PAR
  VSS32  = GND
  CA0_B  = M_L_CPU0_SB_CA<0>
  VSS33  = GND
  CA2_B  = M_L_CPU0_SB_CA<2>
  VSS34  = GND
  CA4_B  = M_L_CPU0_SB_CA<4>
  VSS35  = GND
  CA6_B  = M_L_CPU0_SB_CA<6>
  VSS36  = GND
  CS0_B_N  = M_L_CPU0_SB_CS_N<0>
  VSS37  = GND
  \lbd||rsp_a_n\  = M_L_CPU0_SA_RSP<0>
  \lbs||rsp_b_n\  = M_L_CPU0_SB_RSP<0>
  VSS38  = GND
  CB4_B  = M_L_CPU0_SB_CB<4>
  VSS39  = GND
  CB5_B  = M_L_CPU0_SB_CB<5>
  VSS40  = GND
  \dqs9_b_t||tdqs9_b_t||dbi4_b_n\  = M_L_CPU0_SB_DQS_DP<9>
  \dqs9_b_c||tdqs9_b_c\  = M_L_CPU0_SB_DQS_DN<9>
  VSS41  = GND
  CB0_B  = M_L_CPU0_SB_CB<0>
  VSS42  = GND
  CB1_B  = M_L_CPU0_SB_CB<1>
  VSS43  = GND
  DQ0_B  = M_L_CPU0_SB_DQ<0>
  VSS44  = GND
  DQ1_B  = M_L_CPU0_SB_DQ<1>
  VSS45  = GND
  DQS0_B_T  = M_L_CPU0_SB_DQS_DP<0>
  DQS0_B_C  = M_L_CPU0_SB_DQS_DN<0>
  VSS46  = GND
  DQ4_B  = M_L_CPU0_SB_DQ<4>
  VSS47  = GND
  DQ5_B  = M_L_CPU0_SB_DQ<5>
  VSS48  = GND
  DQ8_B  = M_L_CPU0_SB_DQ<8>
  VSS49  = GND
  DQ9_B  = M_L_CPU0_SB_DQ<9>
  VSS50  = GND
  DQS1_B_T  = M_L_CPU0_SB_DQS_DP<1>
  DQS1_B_C  = M_L_CPU0_SB_DQS_DN<1>
  VSS51  = GND
  DQ12_B  = M_L_CPU0_SB_DQ<12>
  VSS52  = GND
  DQ13_B  = M_L_CPU0_SB_DQ<13>
  VSS53  = GND
  DQ16_B  = M_L_CPU0_SB_DQ<16>
  VSS54  = GND
  DQ17_B  = M_L_CPU0_SB_DQ<17>
  VSS55  = GND
  DQS2_B_T  = M_L_CPU0_SB_DQS_DP<2>
  DQS2_B_C  = M_L_CPU0_SB_DQS_DN<2>
  VSS56  = GND
  DQ20_B  = M_L_CPU0_SB_DQ<20>
  VSS57  = GND
  DQ21_B  = M_L_CPU0_SB_DQ<21>
  VSS58  = GND
  DQ24_B  = M_L_CPU0_SB_DQ<24>
  VSS59  = GND
  DQ25_B  = M_L_CPU0_SB_DQ<25>
  VSS60  = GND
  DQS3_B_T  = M_L_CPU0_SB_DQS_DP<3>
  DQS3_B_C  = M_L_CPU0_SB_DQS_DN<3>
  VSS61  = GND
  DQ28_B  = M_L_CPU0_SB_DQ<28>
  VSS62  = GND
  DQ29_B  = M_L_CPU0_SB_DQ<29>
  VSS63  = GND
  RFU1  = NC
  VIN_BULK1  = P12V_MEM_CPU0
  VIN_BULK2  = P12V_MEM_CPU0
  \pwr_good||fail_n\  = PWRGD_CHL_CPU0_DIMM
  HAS  = PD_CHL_CPU0_DIMM_SAA
  RFU2  = NC
  RFU3  = NC
  VSS64  = GND
  DQ2_A  = M_L_CPU0_SA_DQ<2>
  VSS65  = GND
  DQ3_A  = M_L_CPU0_SA_DQ<3>
  VSS66  = GND
  \dqs5_a_c||tdqs5_a_c||dqs5_a_t||tdqs5_a_t\  = M_L_CPU0_SA_DQS_DN<5>
  \dqs5_a_t||tdqs5_a_t\  = M_L_CPU0_SA_DQS_DP<5>
  VSS67  = GND
  DQ6_A  = M_L_CPU0_SA_DQ<6>
  VSS68  = GND
  DQ7_A  = M_L_CPU0_SA_DQ<7>
  VSS69  = GND
  DQ10_A  = M_L_CPU0_SA_DQ<10>
  VSS70  = GND
  DQ11_A  = M_L_CPU0_SA_DQ<11>
  VSS71  = GND
  \dqs6_a_c||tdqs6_a_c||dqs6_a_t||tdqs6_a_t\  = M_L_CPU0_SA_DQS_DN<6>
  \dqs6_a_t||tdqs6_a_t\  = M_L_CPU0_SA_DQS_DP<6>
  VSS72  = GND
  DQ14_A  = M_L_CPU0_SA_DQ<14>
  VSS73  = GND
  DQ15_A  = M_L_CPU0_SA_DQ<15>
  VSS74  = GND
  DQ18_A  = M_L_CPU0_SA_DQ<18>
  VSS75  = GND
  DQ19_A  = M_L_CPU0_SA_DQ<19>
  VSS76  = GND
  \dqs7_a_c||tdqs7_a_c\  = M_L_CPU0_SA_DQS_DN<7>
  \dqs7_a_t||tdqs7_a_t\  = M_L_CPU0_SA_DQS_DP<7>
  VSS77  = GND
  DQ22_A  = M_L_CPU0_SA_DQ<22>
  VSS78  = GND
  DQ23_A  = M_L_CPU0_SA_DQ<23>
  VSS79  = GND
  DQ26_A  = M_L_CPU0_SA_DQ<26>
  VSS80  = GND
  DQ27_A  = M_L_CPU0_SA_DQ<27>
  VSS81  = GND
  \dqs8_a_c||tdqs8_a_c\  = M_L_CPU0_SA_DQS_DN<8>
  \dqs8_a_t||tdqs8_a_t\  = M_L_CPU0_SA_DQS_DP<8>
  VSS82  = GND
  DQ30_A  = M_L_CPU0_SA_DQ<30>
  VSS83  = GND
  DQ31_A  = M_L_CPU0_SA_DQ<31>
  VSS84  = GND
  CB2_A  = M_L_CPU0_SA_CB<2>
  VSS85  = GND
  CB3_A  = M_L_CPU0_SA_CB<3>
  VSS86  = GND
  \dqs9_a_c||tdqs9_a_c\  = M_L_CPU0_SA_DQS_DN<9>
  \dqs9_a_t||tdqs9_a_t\  = M_L_CPU0_SA_DQS_DP<9>
  VSS87  = GND
  CB6_A  = M_L_CPU0_SA_CB<6>
  VSS88  = GND
  CB7_A  = M_L_CPU0_SA_CB<7>
  VSS89  = GND
  RESET_N  = M_L_CPU0_RESET_N
  VSS90  = GND
  CS1_A_N  = M_L_CPU0_SA_CS_N<1>
  VSS91  = GND
  CA1_A  = M_L_CPU0_SA_CA<1>
  VSS92  = GND
  CA3_A  = M_L_CPU0_SA_CA<3>
  VSS93  = GND
  CA5_A  = M_L_CPU0_SA_CA<5>
  VSS94  = GND
  CK_T  = M_L_CPU0_CLK_DP<0>
  CK_C  = M_L_CPU0_CLK_DN<0>
  VSS95  = GND
  RFU4  = NC
  CA1_B  = M_L_CPU0_SB_CA<1>
  VSS96  = GND
  CA3_B  = M_L_CPU0_SB_CA<3>
  VSS97  = GND
  CA5_B  = M_L_CPU0_SB_CA<5>
  VSS98  = GND
  PAR_B  = M_L_CPU0_SB_PAR
  VSS99  = GND
  CS1_B_N  = M_L_CPU0_SB_CS_N<1>
  VSS100  = GND
  RFU5  = NC
  RFU6  = NC
  VSS101  = GND
  CB6_B  = M_L_CPU0_SB_CB<6>
  VSS102  = GND
  CB7_B  = M_L_CPU0_SB_CB<7>
  VSS103  = GND
  DQS4_B_C  = M_L_CPU0_SB_DQS_DN<4>
  DQS4_B_T  = M_L_CPU0_SB_DQS_DP<4>
  VSS104  = GND
  CB2_B  = M_L_CPU0_SB_CB<2>
  VSS105  = GND
  CB3_B  = M_L_CPU0_SB_CB<3>
  VSS106  = GND
  DQ2_B  = M_L_CPU0_SB_DQ<2>
  VSS107  = GND
  DQ3_B  = M_L_CPU0_SB_DQ<3>
  VSS108  = GND
  \dqs5_b_c||tdqs5_b_c\  = M_L_CPU0_SB_DQS_DN<5>
  \dqs5_b_t||tdqs5_b_t\  = M_L_CPU0_SB_DQS_DP<5>
  VSS109  = GND
  DQ6_B  = M_L_CPU0_SB_DQ<6>
  VSS110  = GND
  DQ7_B  = M_L_CPU0_SB_DQ<7>
  VSS111  = GND
  DQ10_B  = M_L_CPU0_SB_DQ<10>
  VSS112  = GND
  DQ11_B  = M_L_CPU0_SB_DQ<11>
  VSS113  = GND
  \dqs6_b_c||tdqs6_b_c\  = M_L_CPU0_SB_DQS_DN<6>
  \dqs6_b_t||tdqs6_b_t\  = M_L_CPU0_SB_DQS_DP<6>
  VSS114  = GND
  DQ14_B  = M_L_CPU0_SB_DQ<14>
  VSS115  = GND
  DQ15_B  = M_L_CPU0_SB_DQ<15>
  VSS116  = GND
  DQ18_B  = M_L_CPU0_SB_DQ<18>
  VSS117  = GND
  DQ19_B  = M_L_CPU0_SB_DQ<19>
  VSS118  = GND
  \dqs7_b_c||tdqs7_b_c\  = M_L_CPU0_SB_DQS_DN<7>
  \dqs7_b_t||tdqs7_b_t\  = M_L_CPU0_SB_DQS_DP<7>
  VSS119  = GND
  DQ22_B  = M_L_CPU0_SB_DQ<22>
  VSS120  = GND
  DQ23_B  = M_L_CPU0_SB_DQ<23>
  VSS121  = GND
  DQ26_B  = M_L_CPU0_SB_DQ<26>
  VSS122  = GND
  DQ27_B  = M_L_CPU0_SB_DQ<27>
  VSS123  = GND
  \dqs8_b_c||tdqs8_b_c\  = M_L_CPU0_SB_DQS_DN<8>
  \dqs8_b_t||tdqs8_b_t\  = M_L_CPU0_SB_DQS_DP<8>
  VSS124  = GND
  DQ30_B  = M_L_CPU0_SB_DQ<30>
  VSS125  = GND
  DQ31_B  = M_L_CPU0_SB_DQ<31>
  VSS126  = GND
  G1  = GND
  G2  = GND
  G3  = GND

(kicad_pcb
	(version 20260206)
	(generator "pcbnew")
	(generator_version "10.0")
	(general
		(thickness 1.6)
		(legacy_teardrops no)
	)
	(paper "A4")
	(title_block
		(title "04192023_DAF0TMB3IC0_F0TG_MB_C_brd_V02_OCP.brd")
		(comment 1 "Grand Teton / footprint 3721 of 8354 (J67), pads 277-291 of 291")
	)
	(layers
		(0 "F.Cu" signal "TOP")
		(4 "In1.Cu" signal "GND")
		(6 "In2.Cu" signal "IN1")
		(8 "In3.Cu" signal "GND1")
		(10 "In4.Cu" signal "IN2")
		(12 "In5.Cu" signal "GND2")
		(14 "In6.Cu" signal "IN3")
		(16 "In7.Cu" signal "GND3")
		(18 "In8.Cu" signal "VCC")
		(20 "In9.Cu" signal "VCC1")
		(22 "In10.Cu" signal "GND4")
		(24 "In11.Cu" signal "IN4")
		(26 "In12.Cu" signal "GND5")
		(28 "In13.Cu" signal "IN5")
		(30 "In14.Cu" signal "GND6")
		(32 "In15.Cu" signal "IN6")
		(34 "In16.Cu" signal "GND7")
		(2 "B.Cu" signal "BOTTOM")
		(9 "F.Adhes" user "F.Adhesive")
		(11 "B.Adhes" user "B.Adhesive")
		(13 "F.Paste" user "Package Geometry/Pastemask Top")
		(15 "B.Paste" user "Package Geometry/Pastemask Bottom")
		(5 "F.SilkS" user "Ref Des/Silkscreen Top")
		(7 "B.SilkS" user "Ref Des/Silkscreen Bottom")
		(1 "F.Mask" user "Board Geometry/Soldermask Top")
		(3 "B.Mask" user "Board Geometry/Soldermask Bottom")
		(17 "Dwgs.User" user "User.Drawings")
		(19 "Cmts.User" user "User.Comments")
		(21 "Eco1.User" user "User.Eco1")
		(23 "Eco2.User" user "User.Eco2")
		(25 "Edge.Cuts" user "Board Geometry/Outline")
		(27 "Margin" user)
		(31 "F.CrtYd" user "Package Geometry/Place Bound Top")
		(29 "B.CrtYd" user "Package Geometry/Place Bound Bottom")
		(35 "F.Fab" user "Ref Des/Assembly Top")
		(33 "B.Fab" user "Ref Des/Assembly Bottom")
	)
	(footprint ""
		(layer "F.Cu")
		(at 452.138034 -255.560068 180)
		(property "Reference" "J67"
			(at 2.380488 -81.709768 0)
			(unlocked yes)
			(layer "F.SilkS")
			(effects
				(font
					(size 0.7874 0.5842)
					(thickness 0.1524)
				)
			)
		)
		(property "Value" ""
			(at 0 0 180)
			(layer "F.Fab")
			(effects
				(font
					(size 1.27 1.27)
				)
			)
		)
		(duplicate_pad_numbers_are_jumpers no)
		(pad "277" smd rect
			(at 2.050034 53.975 90)
			(size 0.519938 1.4986)
			(layers "F.Cu" "F.Mask" "F.Paste")
			(net "GND")
		)
		(pad "278" smd rect
			(at 2.050034 54.824884 90)
			(size 0.519938 1.4986)
			(layers "F.Cu" "F.Mask" "F.Paste")
			(net "M_L_CPU0_SB_DQ<26>")
		)
		(pad "279" smd rect
			(at 2.050034 55.675022 90)
			(size 0.519938 1.4986)
			(layers "F.Cu" "F.Mask" "F.Paste")
			(net "GND")
		)
		(pad "280" smd rect
			(at 2.050034 56.524906 90)
			(size 0.519938 1.4986)
			(layers "F.Cu" "F.Mask" "F.Paste")
			(net "M_L_CPU0_SB_DQ<27>")
		)
		(pad "281" smd rect
			(at 2.050034 57.375044 90)
			(size 0.519938 1.4986)
			(layers "F.Cu" "F.Mask" "F.Paste")
			(net "GND")
		)
		(pad "282" smd rect
			(at 2.050034 58.224928 90)
			(size 0.519938 1.4986)
			(layers "F.Cu" "F.Mask" "F.Paste")
			(net "M_L_CPU0_SB_DQS_DN<8>")
		)
		(pad "283" smd rect
			(at 2.050034 59.075066 90)
			(size 0.519938 1.4986)
			(layers "F.Cu" "F.Mask" "F.Paste")
			(net "M_L_CPU0_SB_DQS_DP<8>")
		)
		(pad "284" smd rect
			(at 2.050034 59.92495 90)
			(size 0.519938 1.4986)
			(layers "F.Cu" "F.Mask" "F.Paste")
			(net "GND")
		)
		(pad "285" smd rect
			(at 2.050034 60.775088 90)
			(size 0.519938 1.4986)
			(layers "F.Cu" "F.Mask" "F.Paste")
			(net "M_L_CPU0_SB_DQ<30>")
		)
		(pad "286" smd rect
			(at 2.050034 61.624972 90)
			(size 0.519938 1.4986)
			(layers "F.Cu" "F.Mask" "F.Paste")
			(net "GND")
		)
		(pad "287" smd rect
			(at 2.050034 62.47511 90)
			(size 0.519938 1.4986)
			(layers "F.Cu" "F.Mask" "F.Paste")
			(net "M_L_CPU0_SB_DQ<31>")
		)
		(pad "288" smd rect
			(at 2.050034 63.324994 90)
			(size 0.519938 1.4986)
			(layers "F.Cu" "F.Mask" "F.Paste")
			(net "GND")
		)
		(pad "G1" thru_hole oval
			(at 0 -68.97497 90)
			(size 1.7272 3.4798)
			(drill oval 1.2192 2.4638)
			(layers "*.Cu" "*.Mask")
			(remove_unused_layers no)
			(net "GND")
			(clearance 0.127)
			(thermal_gap 0.127)
		)
		(pad "G2" thru_hole oval
			(at 0 3.875024 90)
			(size 1.7272 3.4798)
			(drill oval 1.2192 2.4638)
			(layers "*.Cu" "*.Mask")
			(remove_unused_layers no)
			(net "GND")
			(clearance 0.127)
			(thermal_gap 0.127)
		)
		(pad "G3" thru_hole oval
			(at 0 68.97497 90)
			(size 1.7272 3.4798)
			(drill oval 1.2192 2.4638)
			(layers "*.Cu" "*.Mask")
			(remove_unused_layers no)
			(net "GND")
			(clearance 0.127)
			(thermal_gap 0.127)
		)
	)
)
